# S9S_MB_2U (Grand Teton) — schematic netlist excerpt (pin names and nets, part order shuffled) for the footprints in the layout excerpt that follows; sources: Cadence DE-HDL packaged netlist, KiCad conversion of 03242023_DA0F0TMBIJ0_F0T_Motherboard_J_brd_V01_OCP.brd

R2255  Q_RES  0 5% CHIP  pkg 0402LF  page 197 : A = PECI_MUX_SEL_R ; B = FM_PECI_MUX_SEL_N
C1861  Q_CAP  0.1UF 25V 10% X7R  pkg 0402  page 238 : A = P3V3_OCP_V3_2 ; B = GND

(kicad_pcb
	(version 20260206)
	(generator "pcbnew")
	(generator_version "10.0")
	(general
		(thickness 1.6)
		(legacy_teardrops no)
	)
	(paper "A4")
	(title_block
		(title "03242023_DA0F0TMBIJ0_F0T_Motherboard_J_brd_V01_OCP.brd")
		(comment 1 "Grand Teton / footprints 3941-3942 of 6105")
	)
	(layers
		(0 "F.Cu" signal "TOP")
		(4 "In1.Cu" signal "GND")
		(6 "In2.Cu" signal "IN1")
		(8 "In3.Cu" signal "GND1")
		(10 "In4.Cu" signal "IN2")
		(12 "In5.Cu" signal "GND2")
		(14 "In6.Cu" signal "IN3")
		(16 "In7.Cu" signal "GND3")
		(18 "In8.Cu" signal "VCC")
		(20 "In9.Cu" signal "VCC1")
		(22 "In10.Cu" signal "GND4")
		(24 "In11.Cu" signal "IN4")
		(26 "In12.Cu" signal "GND5")
		(28 "In13.Cu" signal "IN5")
		(30 "In14.Cu" signal "GND6")
		(32 "In15.Cu" signal "IN6")
		(34 "In16.Cu" signal "GND7")
		(2 "B.Cu" signal "BOTTOM")
		(9 "F.Adhes" user "F.Adhesive")
		(11 "B.Adhes" user "B.Adhesive")
		(13 "F.Paste" user "Package Geometry/Pastemask Top")
		(15 "B.Paste" user "Package Geometry/Pastemask Bottom")
		(5 "F.SilkS" user "Ref Des/Silkscreen Top")
		(7 "B.SilkS" user "Ref Des/Silkscreen Bottom")
		(1 "F.Mask" user "Board Geometry/Soldermask Top")
		(3 "B.Mask" user "Board Geometry/Soldermask Bottom")
		(17 "Dwgs.User" user "User.Drawings")
		(19 "Cmts.User" user "User.Comments")
		(21 "Eco1.User" user "User.Eco1")
		(23 "Eco2.User" user "User.Eco2")
		(25 "Edge.Cuts" user "Board Geometry/Outline")
		(27 "Margin" user)
		(31 "F.CrtYd" user "Package Geometry/Place Bound Top")
		(29 "B.CrtYd" user "Package Geometry/Place Bound Bottom")
		(35 "F.Fab" user "Ref Des/Assembly Top")
		(33 "B.Fab" user "Ref Des/Assembly Bottom")
	)
	(footprint ""
		(layer "F.Cu")
		(at 304.53965 -62.151768 180)
		(property "Reference" "R2255"
			(at 0 0 180)
			(layer "F.SilkS")
			(hide yes)
			(effects
				(font
					(size 1.27 1.27)
				)
			)
		)
		(property "Value" ""
			(at 0 0 180)
			(layer "F.Fab")
			(effects
				(font
					(size 1.27 1.27)
				)
			)
		)
		(duplicate_pad_numbers_are_jumpers no)
		(fp_line
			(start 0.7874 0.4064)
			(end -0.7874 0.4064)
			(stroke
				(width 0.1524)
				(type default)
			)
			(layer "F.SilkS")
		)
		(fp_line
			(start 0.7874 -0.4064)
			(end 0.7874 0.4064)
			(stroke
				(width 0.1524)
				(type default)
			)
			(layer "F.SilkS")
		)
		(fp_line
			(start -0.7874 0.4064)
			(end -0.7874 -0.4064)
			(stroke
				(width 0.1524)
				(type default)
			)
			(layer "F.SilkS")
		)
		(fp_line
			(start -0.7874 -0.4064)
			(end 0.7874 -0.4064)
			(stroke
				(width 0.1524)
				(type default)
			)
			(layer "F.SilkS")
		)
		(fp_line
			(start 0.67945 0.3048)
			(end 0.120396 0.3048)
			(stroke
				(width 0.1)
				(type default)
			)
			(layer "F.Fab")
		)
		(fp_line
			(start 0.67945 -0.3048)
			(end 0.67945 0.3048)
			(stroke
				(width 0.1)
				(type default)
			)
			(layer "F.Fab")
		)
		(fp_line
			(start 0.12065 -0.2794)
			(end 0.12065 -0.3048)
			(stroke
				(width 0.1)
				(type default)
			)
			(layer "F.Fab")
		)
		(fp_line
			(start 0.12065 -0.3048)
			(end 0.67945 -0.3048)
			(stroke
				(width 0.1)
				(type default)
			)
			(layer "F.Fab")
		)
		(fp_line
			(start 0.120396 0.3048)
			(end 0.120396 0.2794)
			(stroke
				(width 0.1)
				(type default)
			)
			(layer "F.Fab")
		)
		(fp_line
			(start 0.120396 0.2794)
			(end -0.12065 0.2794)
			(stroke
				(width 0.1)
				(type default)
			)
			(layer "F.Fab")
		)
		(fp_line
			(start -0.12065 0.3048)
			(end -0.67945 0.3048)
			(stroke
				(width 0.1)
				(type default)
			)
			(layer "F.Fab")
		)
		(fp_line
			(start -0.12065 0.2794)
			(end -0.12065 0.3048)
			(stroke
				(width 0.1)
				(type default)
			)
			(layer "F.Fab")
		)
		(fp_line
			(start -0.12065 -0.2794)
			(end 0.12065 -0.2794)
			(stroke
				(width 0.1)
				(type default)
			)
			(layer "F.Fab")
		)
		(fp_line
			(start -0.12065 -0.305054)
			(end -0.12065 -0.2794)
			(stroke
				(width 0.1)
				(type default)
			)
			(layer "F.Fab")
		)
		(fp_line
			(start -0.67945 0.3048)
			(end -0.67945 -0.305054)
			(stroke
				(width 0.1)
				(type default)
			)
			(layer "F.Fab")
		)
		(fp_line
			(start -0.67945 -0.305054)
			(end -0.12065 -0.305054)
			(stroke
				(width 0.1)
				(type default)
			)
			(layer "F.Fab")
		)
		(pad "1" smd circle
			(at -0.40005 0 180)
			(size 0 0)
			(layers "F.Cu" "F.Mask" "F.Paste")
			(net "PECI_MUX_SEL_R")
		)
		(pad "2" smd circle
			(at 0.40005 0 180)
			(size 0 0)
			(layers "F.Cu" "F.Mask" "F.Paste")
			(net "FM_PECI_MUX_SEL_N")
		)
	)
	(footprint ""
		(layer "F.Cu")
		(at 98.33864 -30.434788 180)
		(property "Reference" "C1861"
			(at 0 0 180)
			(layer "F.SilkS")
			(hide yes)
			(effects
				(font
					(size 1.27 1.27)
				)
			)
		)
		(property "Value" ""
			(at 0 0 180)
			(layer "F.Fab")
			(effects
				(font
					(size 1.27 1.27)
				)
			)
		)
		(duplicate_pad_numbers_are_jumpers no)
		(fp_line
			(start 0.7874 0.4064)
			(end -0.7874 0.4064)
			(stroke
				(width 0.1524)
				(type default)
			)
			(layer "F.SilkS")
		)
		(fp_line
			(start 0.7874 -0.4064)
			(end 0.7874 0.4064)
			(stroke
				(width 0.1524)
				(type default)
			)
			(layer "F.SilkS")
		)
		(fp_line
			(start -0.7874 0.4064)
			(end -0.7874 -0.4064)
			(stroke
				(width 0.1524)
				(type default)
			)
			(layer "F.SilkS")
		)
		(fp_line
			(start -0.7874 -0.4064)
			(end 0.7874 -0.4064)
			(stroke
				(width 0.1524)
				(type default)
			)
			(layer "F.SilkS")
		)
		(fp_line
			(start 0.67945 0.3048)
			(end 0.120396 0.3048)
			(stroke
				(width 0.1)
				(type default)
			)
			(layer "F.Fab")
		)
		(fp_line
			(start 0.67945 -0.3048)
			(end 0.67945 0.3048)
			(stroke
				(width 0.1)
				(type default)
			)
			(layer "F.Fab")
		)
		(fp_line
			(start 0.12065 -0.2794)
			(end 0.12065 -0.3048)
			(stroke
				(width 0.1)
				(type default)
			)
			(layer "F.Fab")
		)
		(fp_line
			(start 0.12065 -0.3048)
			(end 0.67945 -0.3048)
			(stroke
				(width 0.1)
				(type default)
			)
			(layer "F.Fab")
		)
		(fp_line
			(start 0.120396 0.3048)
			(end 0.120396 0.2794)
			(stroke
				(width 0.1)
				(type default)
			)
			(layer "F.Fab")
		)
		(fp_line
			(start 0.120396 0.2794)
			(end -0.12065 0.2794)
			(stroke
				(width 0.1)
				(type default)
			)
			(layer "F.Fab")
		)
		(fp_line
			(start -0.12065 0.3048)
			(end -0.67945 0.3048)
			(stroke
				(width 0.1)
				(type default)
			)
			(layer "F.Fab")
		)
		(fp_line
			(start -0.12065 0.2794)
			(end -0.12065 0.3048)
			(stroke
				(width 0.1)
				(type default)
			)
			(layer "F.Fab")
		)
		(fp_line
			(start -0.12065 -0.2794)
			(end 0.12065 -0.2794)
			(stroke
				(width 0.1)
				(type default)
			)
			(layer "F.Fab")
		)
		(fp_line
			(start -0.12065 -0.305054)
			(end -0.12065 -0.2794)
			(stroke
				(width 0.1)
				(type default)
			)
			(layer "F.Fab")
		)
		(fp_line
			(start -0.67945 0.3048)
			(end -0.67945 -0.305054)
			(stroke
				(width 0.1)
				(type default)
			)
			(layer "F.Fab")
		)
		(fp_line
			(start -0.67945 -0.305054)
			(end -0.12065 -0.305054)
			(stroke
				(width 0.1)
				(type default)
			)
			(layer "F.Fab")
		)
		(pad "1" smd circle
			(at -0.40005 0 180)
			(size 0 0)
			(layers "F.Cu" "F.Mask" "F.Paste")
			(net "P3V3_OCP_V3_2")
		)
		(pad "2" smd circle
			(at 0.40005 0 180)
			(size 0 0)
			(layers "F.Cu" "F.Mask" "F.Paste")
			(net "GND")
		)
	)
)
